(kicad_pcb
	(version 20260206)
	(generator "pcbnew")
	(generator_version "10.0")
	(general
		(thickness 1.6)
		(legacy_teardrops no)
	)
	(paper "A4")
	(title_block
		(title "Bryce Canyon_IOM_IOC_16318-2_OCP.brd")
		(comment 1 "Bryce Canyon / footprint 592 of 1605 (U1), pads 468-589 of 896")
	)
	(layers
		(0 "F.Cu" signal "TOP")
		(4 "In1.Cu" signal "L2GND")
		(6 "In2.Cu" signal "L3")
		(8 "In3.Cu" signal "L4VCC")
		(10 "In4.Cu" signal "L5VCC")
		(12 "In5.Cu" signal "L6")
		(14 "In6.Cu" signal "L7GND")
		(2 "B.Cu" signal "BOTTOM")
		(9 "F.Adhes" user "F.Adhesive")
		(11 "B.Adhes" user "B.Adhesive")
		(13 "F.Paste" user "Package Geometry/Pastemask Top")
		(15 "B.Paste" user "Package Geometry/Pastemask Bottom")
		(5 "F.SilkS" user "Ref Des/Silkscreen Top")
		(7 "B.SilkS" user "Ref Des/Silkscreen Bottom")
		(1 "F.Mask" user "Board Geometry/Soldermask Top")
		(3 "B.Mask" user "Board Geometry/Soldermask Bottom")
		(17 "Dwgs.User" user "User.Drawings")
		(19 "Cmts.User" user "User.Comments")
		(21 "Eco1.User" user "User.Eco1")
		(23 "Eco2.User" user "User.Eco2")
		(25 "Edge.Cuts" user "Board Geometry/Outline")
		(27 "Margin" user)
		(31 "F.CrtYd" user "Package Geometry/Place Bound Top")
		(29 "B.CrtYd" user "Package Geometry/Place Bound Bottom")
		(35 "F.Fab" user "Ref Des/Assembly Top")
		(33 "B.Fab" user "Ref Des/Assembly Bottom")
	)
	(footprint ""
		(layer "F.Cu")
		(at 192.79997 -65.099946 180)
		(property "Reference" "U1"
			(at 0 0 180)
			(layer "F.SilkS")
			(hide yes)
			(effects
				(font
					(size 1.27 1.27)
				)
			)
		)
		(property "Value" "SAS3008C0-1-DB-500020657-1-GP"
			(at -20.374102 -5.0292 180)
			(unlocked yes)
			(layer "F.Fab")
			(hide yes)
			(effects
				(font
					(size 1.016 1.016)
					(thickness 0.1524)
				)
			)
		)
		(property "Device Type" "BGA896D25H78"
			(at -20.374102 -6.5532 180)
			(unlocked yes)
			(layer "F.Fab")
			(hide yes)
			(effects
				(font
					(size 1.016 1.016)
					(thickness 0.1524)
				)
			)
		)
		(duplicate_pad_numbers_are_jumpers no)
		(pad "F22" smd circle
			(at 5.199888 -7.599934 180)
			(size 0.3556 0.3556)
			(layers "F.Cu" "F.Mask" "F.Paste")
			(net "GND")
		)
		(pad "F23" smd circle
			(at 5.999988 -7.599934 180)
			(size 0.3556 0.3556)
			(layers "F.Cu" "F.Mask" "F.Paste")
			(net "GND")
		)
		(pad "F24" smd circle
			(at 6.800088 -7.599934 180)
			(size 0.3556 0.3556)
			(layers "F.Cu" "F.Mask" "F.Paste")
			(net "GND")
		)
		(pad "F25" smd circle
			(at 7.599934 -7.599934 180)
			(size 0.3556 0.3556)
			(layers "F.Cu" "F.Mask" "F.Paste")
			(net "GND")
		)
		(pad "F26" smd circle
			(at 8.400034 -7.599934 180)
			(size 0.3556 0.3556)
			(layers "F.Cu" "F.Mask" "F.Paste")
			(net "P1V8")
		)
		(pad "F27" smd circle
			(at 9.19988 -7.599934 180)
			(size 0.3556 0.3556)
			(layers "F.Cu" "F.Mask" "F.Paste")
			(net "GND")
		)
		(pad "F28" smd circle
			(at 9.99998 -7.599934 180)
			(size 0.3556 0.3556)
			(layers "F.Cu" "F.Mask" "F.Paste")
			(net "XM_ADDR_19")
		)
		(pad "F29" smd circle
			(at 10.80008 -7.599934 180)
			(size 0.3556 0.3556)
			(layers "F.Cu" "F.Mask" "F.Paste")
			(net "XM_ADDR_16")
		)
		(pad "F30" smd circle
			(at 11.599926 -7.599934 180)
			(size 0.3556 0.3556)
			(layers "F.Cu" "F.Mask" "F.Paste")
			(net "XM_ADDR_20")
		)
		(pad "G1" smd circle
			(at -11.599926 -6.800088 180)
			(size 0.3556 0.3556)
			(layers "F.Cu" "F.Mask" "F.Paste")
			(net "Net_1253")
		)
		(pad "G2" smd circle
			(at -10.80008 -6.800088 180)
			(size 0.3556 0.3556)
			(layers "F.Cu" "F.Mask" "F.Paste")
			(net "Net_1234")
		)
		(pad "G3" smd circle
			(at -9.99998 -6.800088 180)
			(size 0.3556 0.3556)
			(layers "F.Cu" "F.Mask" "F.Paste")
			(net "Net_1235")
		)
		(pad "G4" smd circle
			(at -9.19988 -6.800088 180)
			(size 0.3556 0.3556)
			(layers "F.Cu" "F.Mask" "F.Paste")
			(net "GND")
		)
		(pad "G5" smd circle
			(at -8.400034 -6.800088 180)
			(size 0.3556 0.3556)
			(layers "F.Cu" "F.Mask" "F.Paste")
			(net "P1V8")
		)
		(pad "G6" smd circle
			(at -7.599934 -6.800088 180)
			(size 0.3556 0.3556)
			(layers "F.Cu" "F.Mask" "F.Paste")
			(net "Net_1236")
		)
		(pad "G7" smd circle
			(at -6.800088 -6.800088 180)
			(size 0.3556 0.3556)
			(layers "F.Cu" "F.Mask" "F.Paste")
			(net "GND")
		)
		(pad "G8" smd circle
			(at -5.999988 -6.800088 180)
			(size 0.3556 0.3556)
			(layers "F.Cu" "F.Mask" "F.Paste")
			(net "GND")
		)
		(pad "G9" smd circle
			(at -5.199888 -6.800088 180)
			(size 0.3556 0.3556)
			(layers "F.Cu" "F.Mask" "F.Paste")
			(net "GND")
		)
		(pad "G10" smd circle
			(at -4.400042 -6.800088 180)
			(size 0.3556 0.3556)
			(layers "F.Cu" "F.Mask" "F.Paste")
			(net "GND")
		)
		(pad "G11" smd circle
			(at -3.599942 -6.800088 180)
			(size 0.3556 0.3556)
			(layers "F.Cu" "F.Mask" "F.Paste")
			(net "GND")
		)
		(pad "G12" smd circle
			(at -2.800096 -6.800088 180)
			(size 0.3556 0.3556)
			(layers "F.Cu" "F.Mask" "F.Paste")
			(net "GND")
		)
		(pad "G13" smd circle
			(at -1.999996 -6.800088 180)
			(size 0.3556 0.3556)
			(layers "F.Cu" "F.Mask" "F.Paste")
			(net "GND")
		)
		(pad "G14" smd circle
			(at -1.199896 -6.800088 180)
			(size 0.3556 0.3556)
			(layers "F.Cu" "F.Mask" "F.Paste")
			(net "GND")
		)
		(pad "G15" smd circle
			(at -0.40005 -6.800088 180)
			(size 0.3556 0.3556)
			(layers "F.Cu" "F.Mask" "F.Paste")
			(net "GND")
		)
		(pad "G16" smd circle
			(at 0.40005 -6.800088 180)
			(size 0.3556 0.3556)
			(layers "F.Cu" "F.Mask" "F.Paste")
			(net "GND")
		)
		(pad "G17" smd circle
			(at 1.199896 -6.800088 180)
			(size 0.3556 0.3556)
			(layers "F.Cu" "F.Mask" "F.Paste")
			(net "GND")
		)
		(pad "G18" smd circle
			(at 1.999996 -6.800088 180)
			(size 0.3556 0.3556)
			(layers "F.Cu" "F.Mask" "F.Paste")
			(net "GND")
		)
		(pad "G19" smd circle
			(at 2.800096 -6.800088 180)
			(size 0.3556 0.3556)
			(layers "F.Cu" "F.Mask" "F.Paste")
			(net "GND")
		)
		(pad "G20" smd circle
			(at 3.599942 -6.800088 180)
			(size 0.3556 0.3556)
			(layers "F.Cu" "F.Mask" "F.Paste")
			(net "GND")
		)
		(pad "G21" smd circle
			(at 4.400042 -6.800088 180)
			(size 0.3556 0.3556)
			(layers "F.Cu" "F.Mask" "F.Paste")
			(net "GND")
		)
		(pad "G22" smd circle
			(at 5.199888 -6.800088 180)
			(size 0.3556 0.3556)
			(layers "F.Cu" "F.Mask" "F.Paste")
			(net "GND")
		)
		(pad "G23" smd circle
			(at 5.999988 -6.800088 180)
			(size 0.3556 0.3556)
			(layers "F.Cu" "F.Mask" "F.Paste")
			(net "GND")
		)
		(pad "G24" smd circle
			(at 6.800088 -6.800088 180)
			(size 0.3556 0.3556)
			(layers "F.Cu" "F.Mask" "F.Paste")
			(net "GND")
		)
		(pad "G25" smd circle
			(at 7.599934 -6.800088 180)
			(size 0.3556 0.3556)
			(layers "F.Cu" "F.Mask" "F.Paste")
			(net "GND")
		)
		(pad "G26" smd circle
			(at 8.400034 -6.800088 180)
			(size 0.3556 0.3556)
			(layers "F.Cu" "F.Mask" "F.Paste")
			(net "GND")
		)
		(pad "G27" smd circle
			(at 9.19988 -6.800088 180)
			(size 0.3556 0.3556)
			(layers "F.Cu" "F.Mask" "F.Paste")
			(net "P1V8")
		)
		(pad "G28" smd circle
			(at 9.99998 -6.800088 180)
			(size 0.3556 0.3556)
			(layers "F.Cu" "F.Mask" "F.Paste")
			(net "XM_ADDR_15")
		)
		(pad "G29" smd circle
			(at 10.80008 -6.800088 180)
			(size 0.3556 0.3556)
			(layers "F.Cu" "F.Mask" "F.Paste")
			(net "XM_ADDR_21")
		)
		(pad "G30" smd circle
			(at 11.599926 -6.800088 180)
			(size 0.3556 0.3556)
			(layers "F.Cu" "F.Mask" "F.Paste")
			(net "XM_DATA_13")
		)
		(pad "H1" smd circle
			(at -11.599926 -5.999988 180)
			(size 0.3556 0.3556)
			(layers "F.Cu" "F.Mask" "F.Paste")
			(net "GND")
		)
		(pad "H2" smd circle
			(at -10.80008 -5.999988 180)
			(size 0.3556 0.3556)
			(layers "F.Cu" "F.Mask" "F.Paste")
			(net "Net_1237")
		)
		(pad "H3" smd circle
			(at -9.99998 -5.999988 180)
			(size 0.3556 0.3556)
			(layers "F.Cu" "F.Mask" "F.Paste")
			(net "Net_1238")
		)
		(pad "H4" smd circle
			(at -9.19988 -5.999988 180)
			(size 0.3556 0.3556)
			(layers "F.Cu" "F.Mask" "F.Paste")
			(net "P1V8")
		)
		(pad "H5" smd circle
			(at -8.400034 -5.999988 180)
			(size 0.3556 0.3556)
			(layers "F.Cu" "F.Mask" "F.Paste")
			(net "GND")
		)
		(pad "H6" smd circle
			(at -7.599934 -5.999988 180)
			(size 0.3556 0.3556)
			(layers "F.Cu" "F.Mask" "F.Paste")
			(net "Net_1239")
		)
		(pad "H7" smd circle
			(at -6.800088 -5.999988 180)
			(size 0.3556 0.3556)
			(layers "F.Cu" "F.Mask" "F.Paste")
			(net "GND")
		)
		(pad "H8" smd circle
			(at -5.999988 -5.999988 180)
			(size 0.3556 0.3556)
			(layers "F.Cu" "F.Mask" "F.Paste")
			(net "GND")
		)
		(pad "H9" smd circle
			(at -5.199888 -5.999988 180)
			(size 0.3556 0.3556)
			(layers "F.Cu" "F.Mask" "F.Paste")
			(net "GND")
		)
		(pad "H10" smd circle
			(at -4.400042 -5.999988 180)
			(size 0.3556 0.3556)
			(layers "F.Cu" "F.Mask" "F.Paste")
			(net "GND")
		)
		(pad "H11" smd circle
			(at -3.599942 -5.999988 180)
			(size 0.3556 0.3556)
			(layers "F.Cu" "F.Mask" "F.Paste")
			(net "GND")
		)
		(pad "H12" smd circle
			(at -2.800096 -5.999988 180)
			(size 0.3556 0.3556)
			(layers "F.Cu" "F.Mask" "F.Paste")
			(net "GND")
		)
		(pad "H13" smd circle
			(at -1.999996 -5.999988 180)
			(size 0.3556 0.3556)
			(layers "F.Cu" "F.Mask" "F.Paste")
			(net "GND")
		)
		(pad "H14" smd circle
			(at -1.199896 -5.999988 180)
			(size 0.3556 0.3556)
			(layers "F.Cu" "F.Mask" "F.Paste")
			(net "GND")
		)
		(pad "H15" smd circle
			(at -0.40005 -5.999988 180)
			(size 0.3556 0.3556)
			(layers "F.Cu" "F.Mask" "F.Paste")
			(net "GND")
		)
		(pad "H16" smd circle
			(at 0.40005 -5.999988 180)
			(size 0.3556 0.3556)
			(layers "F.Cu" "F.Mask" "F.Paste")
			(net "GND")
		)
		(pad "H17" smd circle
			(at 1.199896 -5.999988 180)
			(size 0.3556 0.3556)
			(layers "F.Cu" "F.Mask" "F.Paste")
			(net "GND")
		)
		(pad "H18" smd circle
			(at 1.999996 -5.999988 180)
			(size 0.3556 0.3556)
			(layers "F.Cu" "F.Mask" "F.Paste")
			(net "GND")
		)
		(pad "H19" smd circle
			(at 2.800096 -5.999988 180)
			(size 0.3556 0.3556)
			(layers "F.Cu" "F.Mask" "F.Paste")
			(net "GND")
		)
		(pad "H20" smd circle
			(at 3.599942 -5.999988 180)
			(size 0.3556 0.3556)
			(layers "F.Cu" "F.Mask" "F.Paste")
			(net "GND")
		)
		(pad "H21" smd circle
			(at 4.400042 -5.999988 180)
			(size 0.3556 0.3556)
			(layers "F.Cu" "F.Mask" "F.Paste")
			(net "GND")
		)
		(pad "H22" smd circle
			(at 5.199888 -5.999988 180)
			(size 0.3556 0.3556)
			(layers "F.Cu" "F.Mask" "F.Paste")
			(net "GND")
		)
		(pad "H23" smd circle
			(at 5.999988 -5.999988 180)
			(size 0.3556 0.3556)
			(layers "F.Cu" "F.Mask" "F.Paste")
			(net "GND")
		)
		(pad "H24" smd circle
			(at 6.800088 -5.999988 180)
			(size 0.3556 0.3556)
			(layers "F.Cu" "F.Mask" "F.Paste")
			(net "GND")
		)
		(pad "H25" smd circle
			(at 7.599934 -5.999988 180)
			(size 0.3556 0.3556)
			(layers "F.Cu" "F.Mask" "F.Paste")
			(net "GND")
		)
		(pad "H26" smd circle
			(at 8.400034 -5.999988 180)
			(size 0.3556 0.3556)
			(layers "F.Cu" "F.Mask" "F.Paste")
			(net "P1V8")
		)
		(pad "H27" smd circle
			(at 9.19988 -5.999988 180)
			(size 0.3556 0.3556)
			(layers "F.Cu" "F.Mask" "F.Paste")
			(net "GND")
		)
		(pad "H28" smd circle
			(at 9.99998 -5.999988 180)
			(size 0.3556 0.3556)
			(layers "F.Cu" "F.Mask" "F.Paste")
			(net "XM_DATA_0")
		)
		(pad "H29" smd circle
			(at 10.80008 -5.999988 180)
			(size 0.3556 0.3556)
			(layers "F.Cu" "F.Mask" "F.Paste")
			(net "XM_ADDR_25")
		)
		(pad "H30" smd circle
			(at 11.599926 -5.999988 180)
			(size 0.3556 0.3556)
			(layers "F.Cu" "F.Mask" "F.Paste")
			(net "XM_ADDR_18")
		)
		(pad "J1" smd circle
			(at -11.599926 -5.199888 180)
			(size 0.3556 0.3556)
			(layers "F.Cu" "F.Mask" "F.Paste")
			(net "Net_1254")
		)
		(pad "J2" smd circle
			(at -10.80008 -5.199888 180)
			(size 0.3556 0.3556)
			(layers "F.Cu" "F.Mask" "F.Paste")
			(net "Net_1240")
		)
		(pad "J3" smd circle
			(at -9.99998 -5.199888 180)
			(size 0.3556 0.3556)
			(layers "F.Cu" "F.Mask" "F.Paste")
			(net "Net_1241")
		)
		(pad "J4" smd circle
			(at -9.19988 -5.199888 180)
			(size 0.3556 0.3556)
			(layers "F.Cu" "F.Mask" "F.Paste")
			(net "GND")
		)
		(pad "J5" smd circle
			(at -8.400034 -5.199888 180)
			(size 0.3556 0.3556)
			(layers "F.Cu" "F.Mask" "F.Paste")
			(net "P1V8")
		)
		(pad "J6" smd circle
			(at -7.599934 -5.199888 180)
			(size 0.3556 0.3556)
			(layers "F.Cu" "F.Mask" "F.Paste")
			(net "Net_1242")
		)
		(pad "J7" smd circle
			(at -6.800088 -5.199888 180)
			(size 0.3556 0.3556)
			(layers "F.Cu" "F.Mask" "F.Paste")
			(net "GND")
		)
		(pad "J8" smd circle
			(at -5.999988 -5.199888 180)
			(size 0.3556 0.3556)
			(layers "F.Cu" "F.Mask" "F.Paste")
			(net "GND")
		)
		(pad "J9" smd circle
			(at -5.199888 -5.199888 180)
			(size 0.3556 0.3556)
			(layers "F.Cu" "F.Mask" "F.Paste")
			(net "GND")
		)
		(pad "J10" smd circle
			(at -4.400042 -5.199888 180)
			(size 0.3556 0.3556)
			(layers "F.Cu" "F.Mask" "F.Paste")
			(net "GND")
		)
		(pad "J11" smd circle
			(at -3.599942 -5.199888 180)
			(size 0.3556 0.3556)
			(layers "F.Cu" "F.Mask" "F.Paste")
			(net "GND")
		)
		(pad "J12" smd circle
			(at -2.800096 -5.199888 180)
			(size 0.3556 0.3556)
			(layers "F.Cu" "F.Mask" "F.Paste")
			(net "P0V975")
		)
		(pad "J13" smd circle
			(at -1.999996 -5.199888 180)
			(size 0.3556 0.3556)
			(layers "F.Cu" "F.Mask" "F.Paste")
			(net "GND")
		)
		(pad "J14" smd circle
			(at -1.199896 -5.199888 180)
			(size 0.3556 0.3556)
			(layers "F.Cu" "F.Mask" "F.Paste")
			(net "GND")
		)
		(pad "J15" smd circle
			(at -0.40005 -5.199888 180)
			(size 0.3556 0.3556)
			(layers "F.Cu" "F.Mask" "F.Paste")
			(net "GND")
		)
		(pad "J16" smd circle
			(at 0.40005 -5.199888 180)
			(size 0.3556 0.3556)
			(layers "F.Cu" "F.Mask" "F.Paste")
			(net "GND")
		)
		(pad "J17" smd circle
			(at 1.199896 -5.199888 180)
			(size 0.3556 0.3556)
			(layers "F.Cu" "F.Mask" "F.Paste")
			(net "GND")
		)
		(pad "J18" smd circle
			(at 1.999996 -5.199888 180)
			(size 0.3556 0.3556)
			(layers "F.Cu" "F.Mask" "F.Paste")
			(net "GND")
		)
		(pad "J19" smd circle
			(at 2.800096 -5.199888 180)
			(size 0.3556 0.3556)
			(layers "F.Cu" "F.Mask" "F.Paste")
			(net "GND")
		)
		(pad "J20" smd circle
			(at 3.599942 -5.199888 180)
			(size 0.3556 0.3556)
			(layers "F.Cu" "F.Mask" "F.Paste")
			(net "GND")
		)
		(pad "J21" smd circle
			(at 4.400042 -5.199888 180)
			(size 0.3556 0.3556)
			(layers "F.Cu" "F.Mask" "F.Paste")
			(net "GND")
		)
		(pad "J22" smd circle
			(at 5.199888 -5.199888 180)
			(size 0.3556 0.3556)
			(layers "F.Cu" "F.Mask" "F.Paste")
			(net "GND")
		)
		(pad "J23" smd circle
			(at 5.999988 -5.199888 180)
			(size 0.3556 0.3556)
			(layers "F.Cu" "F.Mask" "F.Paste")
			(net "GND")
		)
		(pad "J24" smd circle
			(at 6.800088 -5.199888 180)
			(size 0.3556 0.3556)
			(layers "F.Cu" "F.Mask" "F.Paste")
			(net "GND")
		)
		(pad "J25" smd circle
			(at 7.599934 -5.199888 180)
			(size 0.3556 0.3556)
			(layers "F.Cu" "F.Mask" "F.Paste")
			(net "GND")
		)
		(pad "J26" smd circle
			(at 8.400034 -5.199888 180)
			(size 0.3556 0.3556)
			(layers "F.Cu" "F.Mask" "F.Paste")
			(net "GND")
		)
		(pad "J27" smd circle
			(at 9.19988 -5.199888 180)
			(size 0.3556 0.3556)
			(layers "F.Cu" "F.Mask" "F.Paste")
			(net "P1V8")
		)
		(pad "J28" smd circle
			(at 9.99998 -5.199888 180)
			(size 0.3556 0.3556)
			(layers "F.Cu" "F.Mask" "F.Paste")
			(net "XM_DATA_12")
		)
		(pad "J29" smd circle
			(at 10.80008 -5.199888 180)
			(size 0.3556 0.3556)
			(layers "F.Cu" "F.Mask" "F.Paste")
			(net "XM_ADDR_22")
		)
		(pad "J30" smd circle
			(at 11.599926 -5.199888 180)
			(size 0.3556 0.3556)
			(layers "F.Cu" "F.Mask" "F.Paste")
			(net "XM_ADDR_24")
		)
		(pad "K1" smd circle
			(at -11.599926 -4.400042 180)
			(size 0.3556 0.3556)
			(layers "F.Cu" "F.Mask" "F.Paste")
			(net "SIO_LOAD_1")
		)
		(pad "K2" smd circle
			(at -10.80008 -4.400042 180)
			(size 0.3556 0.3556)
			(layers "F.Cu" "F.Mask" "F.Paste")
			(net "SIO_DOUT_0")
		)
		(pad "K3" smd circle
			(at -9.99998 -4.400042 180)
			(size 0.3556 0.3556)
			(layers "F.Cu" "F.Mask" "F.Paste")
			(net "GND")
		)
		(pad "K4" smd circle
			(at -9.19988 -4.400042 180)
			(size 0.3556 0.3556)
			(layers "F.Cu" "F.Mask" "F.Paste")
			(net "P1V8")
		)
		(pad "K5" smd circle
			(at -8.400034 -4.400042 180)
			(size 0.3556 0.3556)
			(layers "F.Cu" "F.Mask" "F.Paste")
			(net "GND")
		)
		(pad "K6" smd circle
			(at -7.599934 -4.400042 180)
			(size 0.3556 0.3556)
			(layers "F.Cu" "F.Mask" "F.Paste")
			(net "Net_1243")
		)
		(pad "K7" smd circle
			(at -6.800088 -4.400042 180)
			(size 0.3556 0.3556)
			(layers "F.Cu" "F.Mask" "F.Paste")
			(net "GND")
		)
		(pad "K8" smd circle
			(at -5.999988 -4.400042 180)
			(size 0.3556 0.3556)
			(layers "F.Cu" "F.Mask" "F.Paste")
			(net "GND")
		)
		(pad "K9" smd circle
			(at -5.199888 -4.400042 180)
			(size 0.3556 0.3556)
			(layers "F.Cu" "F.Mask" "F.Paste")
			(net "GND")
		)
		(pad "K10" smd circle
			(at -4.400042 -4.400042 180)
			(size 0.3556 0.3556)
			(layers "F.Cu" "F.Mask" "F.Paste")
			(net "GND")
		)
		(pad "K11" smd circle
			(at -3.599942 -4.400042 180)
			(size 0.3556 0.3556)
			(layers "F.Cu" "F.Mask" "F.Paste")
			(net "GND")
		)
		(pad "K12" smd circle
			(at -2.800096 -4.400042 180)
			(size 0.3556 0.3556)
			(layers "F.Cu" "F.Mask" "F.Paste")
			(net "GND")
		)
		(pad "K13" smd circle
			(at -1.999996 -4.400042 180)
			(size 0.3556 0.3556)
			(layers "F.Cu" "F.Mask" "F.Paste")
			(net "P0V975")
		)
		(pad "K14" smd circle
			(at -1.199896 -4.400042 180)
			(size 0.3556 0.3556)
			(layers "F.Cu" "F.Mask" "F.Paste")
			(net "GND")
		)
		(pad "K15" smd circle
			(at -0.40005 -4.400042 180)
			(size 0.3556 0.3556)
			(layers "F.Cu" "F.Mask" "F.Paste")
			(net "GND")
		)
		(pad "K16" smd circle
			(at 0.40005 -4.400042 180)
			(size 0.3556 0.3556)
			(layers "F.Cu" "F.Mask" "F.Paste")
			(net "GND")
		)
		(pad "K17" smd circle
			(at 1.199896 -4.400042 180)
			(size 0.3556 0.3556)
			(layers "F.Cu" "F.Mask" "F.Paste")
			(net "GND")
		)
		(pad "K18" smd circle
			(at 1.999996 -4.400042 180)
			(size 0.3556 0.3556)
			(layers "F.Cu" "F.Mask" "F.Paste")
			(net "GND")
		)
		(pad "K19" smd circle
			(at 2.800096 -4.400042 180)
			(size 0.3556 0.3556)
			(layers "F.Cu" "F.Mask" "F.Paste")
			(net "GND")
		)
		(pad "K20" smd circle
			(at 3.599942 -4.400042 180)
			(size 0.3556 0.3556)
			(layers "F.Cu" "F.Mask" "F.Paste")
			(net "GND")
		)
		(pad "K21" smd circle
			(at 4.400042 -4.400042 180)
			(size 0.3556 0.3556)
			(layers "F.Cu" "F.Mask" "F.Paste")
			(net "P0V975")
		)
		(pad "K22" smd circle
			(at 5.199888 -4.400042 180)
			(size 0.3556 0.3556)
			(layers "F.Cu" "F.Mask" "F.Paste")
			(net "GND")
		)
		(pad "K23" smd circle
			(at 5.999988 -4.400042 180)
			(size 0.3556 0.3556)
			(layers "F.Cu" "F.Mask" "F.Paste")
			(net "GND")
		)
	)
)
